#ISCELL
  pure_quanta quanta_title_block_c *
  *
#CELL
  pure_quanta pt5161lrs *
  page428_i1
#ISCELL
  standard tap *
  page428_i10
#ISCELL
  standard tap *
  page428_i11
#ISCELL
  standard tap *
  page428_i12
#ISCELL
  standard tap *
  page428_i13
#ISCELL
  standard tap *
  page428_i14
#ISCELL
  standard tap *
  page428_i15
#ISCELL
  standard tap *
  page428_i16
#ISCELL
  standard tap *
  page428_i17
#ISCELL
  standard offpage *
  page428_i18
#ISCELL
  standard offpage *
  page428_i19
#ISCELL
  standard tap *
  page428_i2
#ISCELL
  standard tap *
  page428_i20
#ISCELL
  standard tap *
  page428_i21
#ISCELL
  standard tap *
  page428_i22
#ISCELL
  standard tap *
  page428_i23
#ISCELL
  standard tap *
  page428_i24
#ISCELL
  standard tap *
  page428_i25
#ISCELL
  standard tap *
  page428_i26
#ISCELL
  standard tap *
  page428_i27
#ISCELL
  standard tap *
  page428_i28
#ISCELL
  standard tap *
  page428_i29
#ISCELL
  standard tap *
  page428_i3
#ISCELL
  standard tap *
  page428_i30
#ISCELL
  standard tap *
  page428_i31
#ISCELL
  standard tap *
  page428_i32
#ISCELL
  standard tap *
  page428_i33
#ISCELL
  standard tap *
  page428_i34
#ISCELL
  standard tap *
  page428_i35
#ISCELL
  standard offpage *
  page428_i36
#ISCELL
  standard offpage *
  page428_i37
#CELL
  pure_quanta pt5161lrs *
  page428_i38
#ISCELL
  standard tap *
  page428_i4
#ISCELL
  standard tap *
  page428_i5
#ISCELL
  standard tap *
  page428_i6
#ISCELL
  standard tap *
  page428_i7
#ISCELL
  standard tap *
  page428_i8
#ISCELL
  standard tap *
  page428_i9
